(kicad_pcb
	(version 20260206)
	(generator "pcbnew")
	(generator_version "10.0")
	(general
		(thickness 1.6)
		(legacy_teardrops no)
	)
	(paper "A4")
	(title_block
		(title "Bryce Canyon_F.DPB_16315-1-OCP.brd")
		(comment 1 "Bryce Canyon / footprints 1925-1932 of 2223")
	)
	(layers
		(0 "F.Cu" signal "TOP")
		(4 "In1.Cu" signal "L2GND")
		(6 "In2.Cu" signal "L3")
		(8 "In3.Cu" signal "L4GND")
		(10 "In4.Cu" signal "L5")
		(12 "In5.Cu" signal "L6VCC")
		(14 "In6.Cu" signal "L7VCC")
		(16 "In7.Cu" signal "L8")
		(18 "In8.Cu" signal "L9GND")
		(20 "In9.Cu" signal "L10")
		(22 "In10.Cu" signal "L11GND")
		(2 "B.Cu" signal "BOTTOM")
		(9 "F.Adhes" user "F.Adhesive")
		(11 "B.Adhes" user "B.Adhesive")
		(13 "F.Paste" user "Package Geometry/Pastemask Top")
		(15 "B.Paste" user "Package Geometry/Pastemask Bottom")
		(5 "F.SilkS" user "Ref Des/Silkscreen Top")
		(7 "B.SilkS" user "Ref Des/Silkscreen Bottom")
		(1 "F.Mask" user "Board Geometry/Soldermask Top")
		(3 "B.Mask" user "Board Geometry/Soldermask Bottom")
		(17 "Dwgs.User" user "User.Drawings")
		(19 "Cmts.User" user "User.Comments")
		(21 "Eco1.User" user "User.Eco1")
		(23 "Eco2.User" user "User.Eco2")
		(25 "Edge.Cuts" user "Board Geometry/Outline")
		(27 "Margin" user)
		(31 "F.CrtYd" user "Package Geometry/Place Bound Top")
		(29 "B.CrtYd" user "Package Geometry/Place Bound Bottom")
		(35 "F.Fab" user "Ref Des/Assembly Top")
		(33 "B.Fab" user "Ref Des/Assembly Bottom")
	)
	(footprint ""
		(layer "F.Cu")
		(at 404.400004 -289.999928)
		(property "Reference" ""
			(at 0 0 0)
			(layer "F.SilkS")
			(hide yes)
			(effects
				(font
					(size 1.27 1.27)
				)
			)
		)
		(property "Value" "*"
			(at -6.3373 -0.4572 0)
			(unlocked yes)
			(layer "F.Fab")
			(hide yes)
			(effects
				(font
					(size 1.016 1.016)
					(thickness 0.1524)
				)
			)
		)
		(duplicate_pad_numbers_are_jumpers no)
		(fp_poly
			(pts
				(arc
					(start 5.0673 0)
					(mid -5.0673 0)
					(end 5.0673 0)
				)
			)
			(stroke
				(width 0)
				(type default)
			)
			(fill no)
			(layer "B.CrtYd")
		)
		(fp_poly
			(pts
				(arc
					(start 5.0673 0)
					(mid -5.0673 0)
					(end 5.0673 0)
				)
			)
			(stroke
				(width 0)
				(type default)
			)
			(fill no)
			(layer "F.CrtYd")
		)
		(fp_poly
			(pts
				(arc
					(start 5.0673 0)
					(mid -5.0673 0)
					(end 5.0673 0)
				)
			)
			(stroke
				(width 0)
				(type default)
			)
			(fill no)
			(layer "B.Fab")
		)
		(fp_poly
			(pts
				(arc
					(start 5.0673 0)
					(mid -5.0673 0)
					(end 5.0673 0)
				)
			)
			(stroke
				(width 0)
				(type default)
			)
			(fill no)
			(layer "F.Fab")
		)
		(pad "1" thru_hole circle
			(at 0 0)
			(size 9.525 9.525)
			(drill 3.556)
			(layers "*.Cu" "*.Mask")
			(remove_unused_layers no)
			(net "Net_94")
			(clearance -2.4765)
			(thermal_gap 0.3048)
			(padstack
				(mode front_inner_back)
				(layer "Inner"
					(shape circle)
					(size 3.9624 3.9624)
					(clearance 0.3048)
				)
				(layer "B.Cu"
					(shape circle)
					(size 9.525 9.525)
					(clearance -2.4765)
				)
			)
		)
		(zone
			(layers "F.Cu" "B.Cu" "In1.Cu" "In2.Cu" "In3.Cu" "In4.Cu" "In5.Cu" "In6.Cu"
				"In7.Cu" "In8.Cu" "In9.Cu" "In10.Cu"
			)
			(hatch none 0.5)
			(connect_pads
				(clearance 0)
			)
			(min_thickness 0.25)
			(keepout
				(tracks not_allowed)
				(vias allowed)
				(pads allowed)
				(copperpour not_allowed)
				(footprints allowed)
			)
			(placement
				(enabled no)
				(sheetname "")
			)
			(fill
				(thermal_gap 0.5)
				(thermal_bridge_width 0.5)
				(island_removal_mode 0)
			)
			(polygon
				(pts
					(arc
						(start 409.162504 -289.999928)
						(mid 399.637504 -289.999928)
						(end 409.162504 -289.999928)
					)
				)
			)
		)
	)
	(footprint ""
		(layer "F.Cu")
		(at 364.290102 -278.554942 -90)
		(property "Reference" "R298"
			(at 0 0 270)
			(layer "F.SilkS")
			(hide yes)
			(effects
				(font
					(size 1.27 1.27)
				)
			)
		)
		(property "Value" "4K7R2J-2-GP"
			(at 0.064008 -3.993896 270)
			(unlocked yes)
			(layer "F.Fab")
			(hide yes)
			(effects
				(font
					(size 1.016 1.016)
					(thickness 0.1524)
				)
			)
		)
		(property "Device Type" "R402H16"
			(at 0.064008 -5.517896 270)
			(unlocked yes)
			(layer "F.Fab")
			(hide yes)
			(effects
				(font
					(size 1.016 1.016)
					(thickness 0.1524)
				)
			)
		)
		(duplicate_pad_numbers_are_jumpers no)
		(fp_line
			(start -0.508 -0.9398)
			(end -0.508 0.9398)
			(stroke
				(width 0.1524)
				(type default)
			)
			(layer "F.SilkS")
		)
		(fp_line
			(start 0.508 -0.9398)
			(end -0.508 -0.9398)
			(stroke
				(width 0.1524)
				(type default)
			)
			(layer "F.SilkS")
		)
		(fp_rect
			(start -0.508 0.9398)
			(end 0.508 -0.9398)
			(stroke
				(width 0)
				(type default)
			)
			(fill no)
			(layer "F.CrtYd")
		)
		(fp_rect
			(start -0.508 0.9398)
			(end 0.508 -0.9398)
			(stroke
				(width 0)
				(type default)
			)
			(fill no)
			(layer "F.Fab")
		)
		(pad "1" smd custom
			(at 0 -0.4445 270)
			(size 0.1397 0.1397)
			(layers "F.Cu" "F.Mask" "F.Paste")
			(net "P12V_A")
			(options
				(clearance outline)
				(anchor circle)
			)
			(primitives
				(gr_poly
					(pts
						(arc
							(start -0.1778 -0.2794)
							(mid -0.249642 -0.249642)
							(end -0.2794 -0.1778)
						)
						(arc
							(start -0.2794 0.1778)
							(mid -0.249642 0.249642)
							(end -0.1778 0.2794)
						)
						(arc
							(start 0.1778 0.2794)
							(mid 0.249642 0.249642)
							(end 0.2794 0.1778)
						)
						(arc
							(start 0.2794 -0.1778)
							(mid 0.249642 -0.249642)
							(end 0.1778 -0.2794)
						)
					)
					(width 0)
					(fill yes)
				)
			)
		)
		(pad "2" smd custom
			(at 0 0.4445 270)
			(size 0.1397 0.1397)
			(layers "F.Cu" "F.Mask" "F.Paste")
			(net "SW_HDD_P7")
			(options
				(clearance outline)
				(anchor circle)
			)
			(primitives
				(gr_poly
					(pts
						(arc
							(start -0.1778 -0.2794)
							(mid -0.249642 -0.249642)
							(end -0.2794 -0.1778)
						)
						(arc
							(start -0.2794 0.1778)
							(mid -0.249642 0.249642)
							(end -0.1778 0.2794)
						)
						(arc
							(start 0.1778 0.2794)
							(mid 0.249642 0.249642)
							(end 0.2794 0.1778)
						)
						(arc
							(start 0.2794 -0.1778)
							(mid 0.249642 -0.249642)
							(end 0.1778 -0.2794)
						)
					)
					(width 0)
					(fill yes)
				)
			)
		)
	)
	(footprint ""
		(layer "F.Cu")
		(at 428.152052 -73.954894 180)
		(property "Reference" "C475"
			(at 0 0 180)
			(layer "F.SilkS")
			(hide yes)
			(effects
				(font
					(size 1.27 1.27)
				)
			)
		)
		(property "Value" "SC4D7U25V5KX-1-GP"
			(at -0.0762 -6.1214 180)
			(unlocked yes)
			(layer "F.Fab")
			(hide yes)
			(effects
				(font
					(size 1.016 1.016)
					(thickness 0.1524)
				)
			)
		)
		(property "Device Type" "C805H58"
			(at -0.0762 -8.1534 180)
			(unlocked yes)
			(layer "F.Fab")
			(hide yes)
			(effects
				(font
					(size 1.016 1.016)
					(thickness 0.1524)
				)
			)
		)
		(duplicate_pad_numbers_are_jumpers no)
		(fp_line
			(start 0.635 0)
			(end -0.635 0)
			(stroke
				(width 0.508)
				(type default)
			)
			(layer "F.SilkS")
		)
		(fp_rect
			(start -0.9652 1.778)
			(end 0.9652 -1.778)
			(stroke
				(width 0)
				(type default)
			)
			(fill no)
			(layer "F.CrtYd")
		)
		(fp_poly
			(pts
				(xy -0.9652 -1.778) (xy 0.9652 -1.778) (xy 0.9652 1.778) (xy -0.9652 1.778)
			)
			(stroke
				(width 0)
				(type default)
			)
			(fill no)
			(layer "F.Fab")
		)
		(pad "1" smd rect
			(at 0 -0.9652 180)
			(size 1.397 1.143)
			(layers "F.Cu" "F.Mask" "F.Paste")
			(net "P12V_HDD33")
		)
		(pad "2" smd rect
			(at 0 0.9652 180)
			(size 1.397 1.143)
			(layers "F.Cu" "F.Mask" "F.Paste")
			(net "GND")
		)
	)
	(footprint ""
		(layer "F.Cu")
		(at 86.096348 -48.554894 90)
		(property "Reference" "R740"
			(at 0 0 90)
			(layer "F.SilkS")
			(hide yes)
			(effects
				(font
					(size 1.27 1.27)
				)
			)
		)
		(property "Value" "4K7R2J-2-GP"
			(at 0.064008 -3.993896 90)
			(unlocked yes)
			(layer "F.Fab")
			(hide yes)
			(effects
				(font
					(size 1.016 1.016)
					(thickness 0.1524)
				)
			)
		)
		(property "Device Type" "R402H16"
			(at 0.064008 -5.517896 90)
			(unlocked yes)
			(layer "F.Fab")
			(hide yes)
			(effects
				(font
					(size 1.016 1.016)
					(thickness 0.1524)
				)
			)
		)
		(duplicate_pad_numbers_are_jumpers no)
		(fp_line
			(start 0.508 -0.9398)
			(end -0.508 -0.9398)
			(stroke
				(width 0.1524)
				(type default)
			)
			(layer "F.SilkS")
		)
		(fp_line
			(start -0.508 -0.9398)
			(end -0.508 0.9398)
			(stroke
				(width 0.1524)
				(type default)
			)
			(layer "F.SilkS")
		)
		(fp_rect
			(start -0.508 0.9398)
			(end 0.508 -0.9398)
			(stroke
				(width 0)
				(type default)
			)
			(fill no)
			(layer "F.CrtYd")
		)
		(fp_rect
			(start -0.508 0.9398)
			(end 0.508 -0.9398)
			(stroke
				(width 0)
				(type default)
			)
			(fill no)
			(layer "F.Fab")
		)
		(pad "1" smd custom
			(at 0 -0.4445 90)
			(size 0.1397 0.1397)
			(layers "F.Cu" "F.Mask" "F.Paste")
			(net "SW_PWR_R_HDD26")
			(options
				(clearance outline)
				(anchor circle)
			)
			(primitives
				(gr_poly
					(pts
						(arc
							(start -0.1778 -0.2794)
							(mid -0.249642 -0.249642)
							(end -0.2794 -0.1778)
						)
						(arc
							(start -0.2794 0.1778)
							(mid -0.249642 0.249642)
							(end -0.1778 0.2794)
						)
						(arc
							(start 0.1778 0.2794)
							(mid 0.249642 0.249642)
							(end 0.2794 0.1778)
						)
						(arc
							(start 0.2794 -0.1778)
							(mid 0.249642 -0.249642)
							(end 0.1778 -0.2794)
						)
					)
					(width 0)
					(fill yes)
				)
			)
		)
		(pad "2" smd custom
			(at 0 0.4445 90)
			(size 0.1397 0.1397)
			(layers "F.Cu" "F.Mask" "F.Paste")
			(net "GND")
			(options
				(clearance outline)
				(anchor circle)
			)
			(primitives
				(gr_poly
					(pts
						(arc
							(start -0.1778 -0.2794)
							(mid -0.249642 -0.249642)
							(end -0.2794 -0.1778)
						)
						(arc
							(start -0.2794 0.1778)
							(mid -0.249642 0.249642)
							(end -0.1778 0.2794)
						)
						(arc
							(start 0.1778 0.2794)
							(mid 0.249642 0.249642)
							(end 0.2794 0.1778)
						)
						(arc
							(start 0.2794 -0.1778)
							(mid 0.249642 -0.249642)
							(end 0.1778 -0.2794)
						)
					)
					(width 0)
					(fill yes)
				)
			)
		)
	)
	(footprint ""
		(layer "F.Cu")
		(at 307.64607 -294.435276 180)
		(property "Reference" "R278"
			(at 0 0 180)
			(layer "F.SilkS")
			(hide yes)
			(effects
				(font
					(size 1.27 1.27)
				)
			)
		)
		(property "Value" "91R3F-1-GP"
			(at -0.0254 -2.5146 180)
			(unlocked yes)
			(layer "F.Fab")
			(hide yes)
			(effects
				(font
					(size 1.016 1.016)
					(thickness 0.1524)
				)
			)
		)
		(property "Device Type" "R603H22"
			(at -0.0254 -4.0386 180)
			(unlocked yes)
			(layer "F.Fab")
			(hide yes)
			(effects
				(font
					(size 1.016 1.016)
					(thickness 0.1524)
				)
			)
		)
		(duplicate_pad_numbers_are_jumpers no)
		(fp_line
			(start 0.2032 0)
			(end 0.4826 0)
			(stroke
				(width 0.2032)
				(type default)
			)
			(layer "F.SilkS")
		)
		(fp_line
			(start -0.4826 0)
			(end -0.2032 0)
			(stroke
				(width 0.2032)
				(type default)
			)
			(layer "F.SilkS")
		)
		(fp_rect
			(start -0.5842 1.3335)
			(end 0.5842 -1.3335)
			(stroke
				(width 0)
				(type default)
			)
			(fill no)
			(layer "F.CrtYd")
		)
		(fp_rect
			(start -0.5842 1.3335)
			(end 0.5842 -1.3335)
			(stroke
				(width 0)
				(type default)
			)
			(fill no)
			(layer "F.Fab")
		)
		(pad "1" smd custom
			(at 0 -0.762 180)
			(size 0.2159 0.2159)
			(layers "F.Cu" "F.Mask" "F.Paste")
			(net "P5V_B")
			(options
				(clearance outline)
				(anchor circle)
			)
			(primitives
				(gr_poly
					(pts
						(arc
							(start -0.3302 -0.4318)
							(mid -0.402042 -0.402042)
							(end -0.4318 -0.3302)
						)
						(arc
							(start -0.4318 0.3302)
							(mid -0.402042 0.402042)
							(end -0.3302 0.4318)
						)
						(arc
							(start 0.3302 0.4318)
							(mid 0.402042 0.402042)
							(end 0.4318 0.3302)
						)
						(arc
							(start 0.4318 -0.3302)
							(mid 0.402042 -0.402042)
							(end 0.3302 -0.4318)
						)
					)
					(width 0)
					(fill yes)
				)
			)
		)
		(pad "2" smd custom
			(at 0 0.762 180)
			(size 0.2159 0.2159)
			(layers "F.Cu" "F.Mask" "F.Paste")
			(net "DRV_ACT_30")
			(options
				(clearance outline)
				(anchor circle)
			)
			(primitives
				(gr_poly
					(pts
						(arc
							(start -0.3302 -0.4318)
							(mid -0.402042 -0.402042)
							(end -0.4318 -0.3302)
						)
						(arc
							(start -0.4318 0.3302)
							(mid -0.402042 0.402042)
							(end -0.3302 0.4318)
						)
						(arc
							(start 0.3302 0.4318)
							(mid 0.402042 0.402042)
							(end 0.4318 0.3302)
						)
						(arc
							(start 0.4318 -0.3302)
							(mid 0.402042 -0.402042)
							(end 0.3302 -0.4318)
						)
					)
					(width 0)
					(fill yes)
				)
			)
		)
	)
	(footprint ""
		(layer "F.Cu")
		(at 133.286754 -295.423336 90)
		(property "Reference" "R563"
			(at 0 0 90)
			(layer "F.SilkS")
			(hide yes)
			(effects
				(font
					(size 1.27 1.27)
				)
			)
		)
		(property "Value" "4K7R2J-2-GP"
			(at 0.064008 -3.993896 90)
			(unlocked yes)
			(layer "F.Fab")
			(hide yes)
			(effects
				(font
					(size 1.016 1.016)
					(thickness 0.1524)
				)
			)
		)
		(property "Device Type" "R402H16"
			(at 0.064008 -5.517896 90)
			(unlocked yes)
			(layer "F.Fab")
			(hide yes)
			(effects
				(font
					(size 1.016 1.016)
					(thickness 0.1524)
				)
			)
		)
		(duplicate_pad_numbers_are_jumpers no)
		(fp_line
			(start 0.508 -0.9398)
			(end -0.508 -0.9398)
			(stroke
				(width 0.1524)
				(type default)
			)
			(layer "F.SilkS")
		)
		(fp_line
			(start -0.508 -0.9398)
			(end -0.508 0.9398)
			(stroke
				(width 0.1524)
				(type default)
			)
			(layer "F.SilkS")
		)
		(fp_rect
			(start -0.508 0.9398)
			(end 0.508 -0.9398)
			(stroke
				(width 0)
				(type default)
			)
			(fill no)
			(layer "F.CrtYd")
		)
		(fp_rect
			(start -0.508 0.9398)
			(end 0.508 -0.9398)
			(stroke
				(width 0)
				(type default)
			)
			(fill no)
			(layer "F.Fab")
		)
		(pad "1" smd custom
			(at 0 -0.4445 90)
			(size 0.1397 0.1397)
			(layers "F.Cu" "F.Mask" "F.Paste")
			(net "DRIVE_B_28_ACT")
			(options
				(clearance outline)
				(anchor circle)
			)
			(primitives
				(gr_poly
					(pts
						(arc
							(start -0.1778 -0.2794)
							(mid -0.249642 -0.249642)
							(end -0.2794 -0.1778)
						)
						(arc
							(start -0.2794 0.1778)
							(mid -0.249642 0.249642)
							(end -0.1778 0.2794)
						)
						(arc
							(start 0.1778 0.2794)
							(mid 0.249642 0.249642)
							(end 0.2794 0.1778)
						)
						(arc
							(start 0.2794 -0.1778)
							(mid 0.249642 -0.249642)
							(end 0.1778 -0.2794)
						)
					)
					(width 0)
					(fill yes)
				)
			)
		)
		(pad "2" smd custom
			(at 0 0.4445 90)
			(size 0.1397 0.1397)
			(layers "F.Cu" "F.Mask" "F.Paste")
			(net "GND")
			(options
				(clearance outline)
				(anchor circle)
			)
			(primitives
				(gr_poly
					(pts
						(arc
							(start -0.1778 -0.2794)
							(mid -0.249642 -0.249642)
							(end -0.2794 -0.1778)
						)
						(arc
							(start -0.2794 0.1778)
							(mid -0.249642 0.249642)
							(end -0.1778 0.2794)
						)
						(arc
							(start 0.1778 0.2794)
							(mid 0.249642 0.249642)
							(end 0.2794 0.1778)
						)
						(arc
							(start 0.2794 -0.1778)
							(mid 0.249642 -0.249642)
							(end 0.1778 -0.2794)
						)
					)
					(width 0)
					(fill yes)
				)
			)
		)
	)
	(footprint ""
		(layer "F.Cu")
		(at 18.500598 -275.633942)
		(property "Reference" "R975"
			(at 0 0 0)
			(layer "F.SilkS")
			(hide yes)
			(effects
				(font
					(size 1.27 1.27)
				)
			)
		)
		(property "Value" "0R2J-2-GP"
			(at 0.064008 -3.993896 0)
			(unlocked yes)
			(layer "F.Fab")
			(hide yes)
			(effects
				(font
					(size 1.016 1.016)
					(thickness 0.1524)
				)
			)
		)
		(property "Device Type" "R402H16"
			(at 0.064008 -5.517896 0)
			(unlocked yes)
			(layer "F.Fab")
			(hide yes)
			(effects
				(font
					(size 1.016 1.016)
					(thickness 0.1524)
				)
			)
		)
		(duplicate_pad_numbers_are_jumpers no)
		(fp_line
			(start -0.508 -0.9398)
			(end -0.508 0.9398)
			(stroke
				(width 0.1524)
				(type default)
			)
			(layer "F.SilkS")
		)
		(fp_line
			(start 0.508 -0.9398)
			(end -0.508 -0.9398)
			(stroke
				(width 0.1524)
				(type default)
			)
			(layer "F.SilkS")
		)
		(fp_rect
			(start -0.508 0.9398)
			(end 0.508 -0.9398)
			(stroke
				(width 0)
				(type default)
			)
			(fill no)
			(layer "F.CrtYd")
		)
		(fp_rect
			(start -0.508 0.9398)
			(end 0.508 -0.9398)
			(stroke
				(width 0)
				(type default)
			)
			(fill no)
			(layer "F.Fab")
		)
		(pad "1" smd custom
			(at 0 -0.4445)
			(size 0.1397 0.1397)
			(layers "F.Cu" "F.Mask" "F.Paste")
			(net "SW_HDD_G0")
			(options
				(clearance outline)
				(anchor circle)
			)
			(primitives
				(gr_poly
					(pts
						(arc
							(start -0.1778 -0.2794)
							(mid -0.249642 -0.249642)
							(end -0.2794 -0.1778)
						)
						(arc
							(start -0.2794 0.1778)
							(mid -0.249642 0.249642)
							(end -0.1778 0.2794)
						)
						(arc
							(start 0.1778 0.2794)
							(mid 0.249642 0.249642)
							(end 0.2794 0.1778)
						)
						(arc
							(start 0.2794 -0.1778)
							(mid 0.249642 -0.249642)
							(end 0.1778 -0.2794)
						)
					)
					(width 0)
					(fill yes)
				)
			)
		)
		(pad "2" smd custom
			(at 0 0.4445)
			(size 0.1397 0.1397)
			(layers "F.Cu" "F.Mask" "F.Paste")
			(net "SW_HDD_R0")
			(options
				(clearance outline)
				(anchor circle)
			)
			(primitives
				(gr_poly
					(pts
						(arc
							(start -0.1778 -0.2794)
							(mid -0.249642 -0.249642)
							(end -0.2794 -0.1778)
						)
						(arc
							(start -0.2794 0.1778)
							(mid -0.249642 0.249642)
							(end -0.1778 0.2794)
						)
						(arc
							(start 0.1778 0.2794)
							(mid 0.249642 0.249642)
							(end 0.2794 0.1778)
						)
						(arc
							(start 0.2794 -0.1778)
							(mid 0.249642 -0.249642)
							(end 0.1778 -0.2794)
						)
					)
					(width 0)
					(fill yes)
				)
			)
		)
	)
	(footprint ""
		(layer "F.Cu")
		(at 402.57222 -245.315486 -90)
		(property "Reference" "R488"
			(at 0 0 270)
			(layer "F.SilkS")
			(hide yes)
			(effects
				(font
					(size 1.27 1.27)
				)
			)
		)
		(property "Value" "4K7R2J-2-GP"
			(at 0.064008 -3.993896 270)
			(unlocked yes)
			(layer "F.Fab")
			(hide yes)
			(effects
				(font
					(size 1.016 1.016)
					(thickness 0.1524)
				)
			)
		)
		(property "Device Type" "R402H16"
			(at 0.064008 -5.517896 270)
			(unlocked yes)
			(layer "F.Fab")
			(hide yes)
			(effects
				(font
					(size 1.016 1.016)
					(thickness 0.1524)
				)
			)
		)
		(duplicate_pad_numbers_are_jumpers no)
		(fp_line
			(start -0.508 -0.9398)
			(end -0.508 0.9398)
			(stroke
				(width 0.1524)
				(type default)
			)
			(layer "F.SilkS")
		)
		(fp_line
			(start 0.508 -0.9398)
			(end -0.508 -0.9398)
			(stroke
				(width 0.1524)
				(type default)
			)
			(layer "F.SilkS")
		)
		(fp_rect
			(start -0.508 0.9398)
			(end 0.508 -0.9398)
			(stroke
				(width 0)
				(type default)
			)
			(fill no)
			(layer "F.CrtYd")
		)
		(fp_rect
			(start -0.508 0.9398)
			(end 0.508 -0.9398)
			(stroke
				(width 0)
				(type default)
			)
			(fill no)
			(layer "F.Fab")
		)
		(pad "1" smd custom
			(at 0 -0.4445 270)
			(size 0.1397 0.1397)
			(layers "F.Cu" "F.Mask" "F.Paste")
			(net "DRIVE_A_9_ACT")
			(options
				(clearance outline)
				(anchor circle)
			)
			(primitives
				(gr_poly
					(pts
						(arc
							(start -0.1778 -0.2794)
							(mid -0.249642 -0.249642)
							(end -0.2794 -0.1778)
						)
						(arc
							(start -0.2794 0.1778)
							(mid -0.249642 0.249642)
							(end -0.1778 0.2794)
						)
						(arc
							(start 0.1778 0.2794)
							(mid 0.249642 0.249642)
							(end 0.2794 0.1778)
						)
						(arc
							(start 0.2794 -0.1778)
							(mid 0.249642 -0.249642)
							(end 0.1778 -0.2794)
						)
					)
					(width 0)
					(fill yes)
				)
			)
		)
		(pad "2" smd custom
			(at 0 0.4445 270)
			(size 0.1397 0.1397)
			(layers "F.Cu" "F.Mask" "F.Paste")
			(net "GND")
			(options
				(clearance outline)
				(anchor circle)
			)
			(primitives
				(gr_poly
					(pts
						(arc
							(start -0.1778 -0.2794)
							(mid -0.249642 -0.249642)
							(end -0.2794 -0.1778)
						)
						(arc
							(start -0.2794 0.1778)
							(mid -0.249642 0.249642)
							(end -0.1778 0.2794)
						)
						(arc
							(start 0.1778 0.2794)
							(mid 0.249642 0.249642)
							(end 0.2794 0.1778)
						)
						(arc
							(start 0.2794 -0.1778)
							(mid 0.249642 -0.249642)
							(end 0.1778 -0.2794)
						)
					)
					(width 0)
					(fill yes)
				)
			)
		)
	)
)
